# S9S_MB_2U (Grand Teton) — schematic netlist excerpt (pin names and nets, part order shuffled) for the footprints in the layout excerpt that follows; sources: Cadence DE-HDL packaged netlist, KiCad conversion of 03242023_DA0F0TMBIJ0_F0T_Motherboard_J_brd_V01_OCP.brd

R3471  Q_RES  10K 1% CHIP  pkg 0402LF  page 147 : A = GPU_WP_HW_CTRL_N ; B = GND
R4617  Q_RES  33.2 1% CHIP  pkg 0402LF  page 164 : A = HP_LVC3_OCP_V3_2_PWRGD ; B = HP_LVC3_OCP_V3_2_PWRGD_R
C924  Q_CAP_DIFFBUS  DIFF BUS_0.22UF 6.3V 20% X6S  pkg C0201  page 173 : \1\ = P5E_CPU0_PE0_TX_C_DN<4> ; \2\ = P5E_CPU0_PE0_TX_DN<4>

(kicad_pcb
	(version 20260206)
	(generator "pcbnew")
	(generator_version "10.0")
	(general
		(thickness 1.6)
		(legacy_teardrops no)
	)
	(paper "A4")
	(title_block
		(title "03242023_DA0F0TMBIJ0_F0T_Motherboard_J_brd_V01_OCP.brd")
		(comment 1 "Grand Teton / footprints 174-176 of 6105")
	)
	(layers
		(0 "F.Cu" signal "TOP")
		(4 "In1.Cu" signal "GND")
		(6 "In2.Cu" signal "IN1")
		(8 "In3.Cu" signal "GND1")
		(10 "In4.Cu" signal "IN2")
		(12 "In5.Cu" signal "GND2")
		(14 "In6.Cu" signal "IN3")
		(16 "In7.Cu" signal "GND3")
		(18 "In8.Cu" signal "VCC")
		(20 "In9.Cu" signal "VCC1")
		(22 "In10.Cu" signal "GND4")
		(24 "In11.Cu" signal "IN4")
		(26 "In12.Cu" signal "GND5")
		(28 "In13.Cu" signal "IN5")
		(30 "In14.Cu" signal "GND6")
		(32 "In15.Cu" signal "IN6")
		(34 "In16.Cu" signal "GND7")
		(2 "B.Cu" signal "BOTTOM")
		(9 "F.Adhes" user "F.Adhesive")
		(11 "B.Adhes" user "B.Adhesive")
		(13 "F.Paste" user "Package Geometry/Pastemask Top")
		(15 "B.Paste" user "Package Geometry/Pastemask Bottom")
		(5 "F.SilkS" user "Ref Des/Silkscreen Top")
		(7 "B.SilkS" user "Ref Des/Silkscreen Bottom")
		(1 "F.Mask" user "Board Geometry/Soldermask Top")
		(3 "B.Mask" user "Board Geometry/Soldermask Bottom")
		(17 "Dwgs.User" user "User.Drawings")
		(19 "Cmts.User" user "User.Comments")
		(21 "Eco1.User" user "User.Eco1")
		(23 "Eco2.User" user "User.Eco2")
		(25 "Edge.Cuts" user "Board Geometry/Outline")
		(27 "Margin" user)
		(31 "F.CrtYd" user "Package Geometry/Place Bound Top")
		(29 "B.CrtYd" user "Package Geometry/Place Bound Bottom")
		(35 "F.Fab" user "Ref Des/Assembly Top")
		(33 "B.Fab" user "Ref Des/Assembly Bottom")
	)
	(footprint ""
		(layer "F.Cu")
		(at 86.741 -41.112948)
		(property "Reference" "R4617"
			(at 0 0 0)
			(layer "F.SilkS")
			(hide yes)
			(effects
				(font
					(size 1.27 1.27)
				)
			)
		)
		(property "Value" ""
			(at 0 0 0)
			(layer "F.Fab")
			(effects
				(font
					(size 1.27 1.27)
				)
			)
		)
		(duplicate_pad_numbers_are_jumpers no)
		(fp_line
			(start -0.7874 -0.4064)
			(end 0.7874 -0.4064)
			(stroke
				(width 0.1524)
				(type default)
			)
			(layer "F.SilkS")
		)
		(fp_line
			(start -0.7874 0.4064)
			(end -0.7874 -0.4064)
			(stroke
				(width 0.1524)
				(type default)
			)
			(layer "F.SilkS")
		)
		(fp_line
			(start 0.7874 -0.4064)
			(end 0.7874 0.4064)
			(stroke
				(width 0.1524)
				(type default)
			)
			(layer "F.SilkS")
		)
		(fp_line
			(start 0.7874 0.4064)
			(end -0.7874 0.4064)
			(stroke
				(width 0.1524)
				(type default)
			)
			(layer "F.SilkS")
		)
		(fp_line
			(start -0.67945 -0.305054)
			(end -0.12065 -0.305054)
			(stroke
				(width 0.1)
				(type default)
			)
			(layer "F.Fab")
		)
		(fp_line
			(start -0.67945 0.3048)
			(end -0.67945 -0.305054)
			(stroke
				(width 0.1)
				(type default)
			)
			(layer "F.Fab")
		)
		(fp_line
			(start -0.12065 -0.305054)
			(end -0.12065 -0.2794)
			(stroke
				(width 0.1)
				(type default)
			)
			(layer "F.Fab")
		)
		(fp_line
			(start -0.12065 -0.2794)
			(end 0.12065 -0.2794)
			(stroke
				(width 0.1)
				(type default)
			)
			(layer "F.Fab")
		)
		(fp_line
			(start -0.12065 0.2794)
			(end -0.12065 0.3048)
			(stroke
				(width 0.1)
				(type default)
			)
			(layer "F.Fab")
		)
		(fp_line
			(start -0.12065 0.3048)
			(end -0.67945 0.3048)
			(stroke
				(width 0.1)
				(type default)
			)
			(layer "F.Fab")
		)
		(fp_line
			(start 0.120396 0.2794)
			(end -0.12065 0.2794)
			(stroke
				(width 0.1)
				(type default)
			)
			(layer "F.Fab")
		)
		(fp_line
			(start 0.120396 0.3048)
			(end 0.120396 0.2794)
			(stroke
				(width 0.1)
				(type default)
			)
			(layer "F.Fab")
		)
		(fp_line
			(start 0.12065 -0.3048)
			(end 0.67945 -0.3048)
			(stroke
				(width 0.1)
				(type default)
			)
			(layer "F.Fab")
		)
		(fp_line
			(start 0.12065 -0.2794)
			(end 0.12065 -0.3048)
			(stroke
				(width 0.1)
				(type default)
			)
			(layer "F.Fab")
		)
		(fp_line
			(start 0.67945 -0.3048)
			(end 0.67945 0.3048)
			(stroke
				(width 0.1)
				(type default)
			)
			(layer "F.Fab")
		)
		(fp_line
			(start 0.67945 0.3048)
			(end 0.120396 0.3048)
			(stroke
				(width 0.1)
				(type default)
			)
			(layer "F.Fab")
		)
		(pad "1" smd circle
			(at -0.40005 0)
			(size 0 0)
			(layers "F.Cu" "F.Mask" "F.Paste")
			(net "HP_LVC3_OCP_V3_2_PWRGD")
		)
		(pad "2" smd circle
			(at 0.40005 0)
			(size 0 0)
			(layers "F.Cu" "F.Mask" "F.Paste")
			(net "HP_LVC3_OCP_V3_2_PWRGD_R")
		)
	)
	(footprint ""
		(layer "F.Cu")
		(at 424.223942 -402.671534 180)
		(property "Reference" "R3471"
			(at 0 0 180)
			(layer "F.SilkS")
			(hide yes)
			(effects
				(font
					(size 1.27 1.27)
				)
			)
		)
		(property "Value" ""
			(at 0 0 180)
			(layer "F.Fab")
			(effects
				(font
					(size 1.27 1.27)
				)
			)
		)
		(duplicate_pad_numbers_are_jumpers no)
		(fp_line
			(start 0.7874 0.4064)
			(end -0.7874 0.4064)
			(stroke
				(width 0.1524)
				(type default)
			)
			(layer "F.SilkS")
		)
		(fp_line
			(start 0.7874 -0.4064)
			(end 0.7874 0.4064)
			(stroke
				(width 0.1524)
				(type default)
			)
			(layer "F.SilkS")
		)
		(fp_line
			(start -0.7874 0.4064)
			(end -0.7874 -0.4064)
			(stroke
				(width 0.1524)
				(type default)
			)
			(layer "F.SilkS")
		)
		(fp_line
			(start -0.7874 -0.4064)
			(end 0.7874 -0.4064)
			(stroke
				(width 0.1524)
				(type default)
			)
			(layer "F.SilkS")
		)
		(fp_line
			(start 0.67945 0.3048)
			(end 0.120396 0.3048)
			(stroke
				(width 0.1)
				(type default)
			)
			(layer "F.Fab")
		)
		(fp_line
			(start 0.67945 -0.3048)
			(end 0.67945 0.3048)
			(stroke
				(width 0.1)
				(type default)
			)
			(layer "F.Fab")
		)
		(fp_line
			(start 0.12065 -0.2794)
			(end 0.12065 -0.3048)
			(stroke
				(width 0.1)
				(type default)
			)
			(layer "F.Fab")
		)
		(fp_line
			(start 0.12065 -0.3048)
			(end 0.67945 -0.3048)
			(stroke
				(width 0.1)
				(type default)
			)
			(layer "F.Fab")
		)
		(fp_line
			(start 0.120396 0.3048)
			(end 0.120396 0.2794)
			(stroke
				(width 0.1)
				(type default)
			)
			(layer "F.Fab")
		)
		(fp_line
			(start 0.120396 0.2794)
			(end -0.12065 0.2794)
			(stroke
				(width 0.1)
				(type default)
			)
			(layer "F.Fab")
		)
		(fp_line
			(start -0.12065 0.3048)
			(end -0.67945 0.3048)
			(stroke
				(width 0.1)
				(type default)
			)
			(layer "F.Fab")
		)
		(fp_line
			(start -0.12065 0.2794)
			(end -0.12065 0.3048)
			(stroke
				(width 0.1)
				(type default)
			)
			(layer "F.Fab")
		)
		(fp_line
			(start -0.12065 -0.2794)
			(end 0.12065 -0.2794)
			(stroke
				(width 0.1)
				(type default)
			)
			(layer "F.Fab")
		)
		(fp_line
			(start -0.12065 -0.305054)
			(end -0.12065 -0.2794)
			(stroke
				(width 0.1)
				(type default)
			)
			(layer "F.Fab")
		)
		(fp_line
			(start -0.67945 0.3048)
			(end -0.67945 -0.305054)
			(stroke
				(width 0.1)
				(type default)
			)
			(layer "F.Fab")
		)
		(fp_line
			(start -0.67945 -0.305054)
			(end -0.12065 -0.305054)
			(stroke
				(width 0.1)
				(type default)
			)
			(layer "F.Fab")
		)
		(pad "1" smd circle
			(at -0.40005 0 180)
			(size 0 0)
			(layers "F.Cu" "F.Mask" "F.Paste")
			(net "GPU_WP_HW_CTRL_N")
		)
		(pad "2" smd circle
			(at 0.40005 0 180)
			(size 0 0)
			(layers "F.Cu" "F.Mask" "F.Paste")
			(net "GND")
		)
	)
	(footprint ""
		(layer "F.Cu")
		(at 338.996528 -408.517344 -90)
		(property "Reference" "C924"
			(at 0 0 270)
			(layer "F.SilkS")
			(hide yes)
			(effects
				(font
					(size 1.27 1.27)
				)
			)
		)
		(property "Value" ""
			(at 0 0 270)
			(layer "F.Fab")
			(effects
				(font
					(size 1.27 1.27)
				)
			)
		)
		(duplicate_pad_numbers_are_jumpers no)
		(fp_line
			(start -0.299974 0.150114)
			(end -0.299974 -0.150114)
			(stroke
				(width 0.1)
				(type default)
			)
			(layer "F.Fab")
		)
		(fp_line
			(start 0.299974 0.150114)
			(end -0.299974 0.150114)
			(stroke
				(width 0.1)
				(type default)
			)
			(layer "F.Fab")
		)
		(fp_line
			(start -0.299974 -0.150114)
			(end 0.299974 -0.150114)
			(stroke
				(width 0.1)
				(type default)
			)
			(layer "F.Fab")
		)
		(fp_line
			(start 0.299974 -0.150114)
			(end 0.299974 0.150114)
			(stroke
				(width 0.1)
				(type default)
			)
			(layer "F.Fab")
		)
		(pad "1" smd rect
			(at -0.2667 0 270)
			(size 0.3048 0.381)
			(layers "F.Cu" "F.Mask" "F.Paste")
			(net "P5E_CPU0_PE0_TX_C_DN<4>")
		)
		(pad "2" smd rect
			(at 0.2667 0 270)
			(size 0.3048 0.381)
			(layers "F.Cu" "F.Mask" "F.Paste")
			(net "P5E_CPU0_PE0_TX_DN<4>")
		)
	)
)
